# T6G (Grand Teton) — schematic netlist excerpt (pin names and nets, part order shuffled) for the footprints in the layout excerpt that follows; sources: Cadence DE-HDL packaged netlist, KiCad conversion of 04192023_DAF0TMB3IC0_F0TG_MB_C_brd_V02_OCP.brd

R6201  Q_RES  0 5% CHIP  pkg 0402LF  page 250 : A = SMB_USB_CPU0_HUB1_SCL_R ; B = SMB_USB_CPU0_HUB1_SCL
PC6633_2  Q_CAP  1UF 25V 10% X6S  pkg C0402  page 365 : A = SW_P12V_AUX_P0V9_RETIMER_CPU1_FLT ; B = GND

(kicad_pcb
	(version 20260206)
	(generator "pcbnew")
	(generator_version "10.0")
	(general
		(thickness 1.6)
		(legacy_teardrops no)
	)
	(paper "A4")
	(title_block
		(title "04192023_DAF0TMB3IC0_F0TG_MB_C_brd_V02_OCP.brd")
		(comment 1 "Grand Teton / footprints 43-44 of 8354")
	)
	(layers
		(0 "F.Cu" signal "TOP")
		(4 "In1.Cu" signal "GND")
		(6 "In2.Cu" signal "IN1")
		(8 "In3.Cu" signal "GND1")
		(10 "In4.Cu" signal "IN2")
		(12 "In5.Cu" signal "GND2")
		(14 "In6.Cu" signal "IN3")
		(16 "In7.Cu" signal "GND3")
		(18 "In8.Cu" signal "VCC")
		(20 "In9.Cu" signal "VCC1")
		(22 "In10.Cu" signal "GND4")
		(24 "In11.Cu" signal "IN4")
		(26 "In12.Cu" signal "GND5")
		(28 "In13.Cu" signal "IN5")
		(30 "In14.Cu" signal "GND6")
		(32 "In15.Cu" signal "IN6")
		(34 "In16.Cu" signal "GND7")
		(2 "B.Cu" signal "BOTTOM")
		(9 "F.Adhes" user "F.Adhesive")
		(11 "B.Adhes" user "B.Adhesive")
		(13 "F.Paste" user "Package Geometry/Pastemask Top")
		(15 "B.Paste" user "Package Geometry/Pastemask Bottom")
		(5 "F.SilkS" user "Ref Des/Silkscreen Top")
		(7 "B.SilkS" user "Ref Des/Silkscreen Bottom")
		(1 "F.Mask" user "Board Geometry/Soldermask Top")
		(3 "B.Mask" user "Board Geometry/Soldermask Bottom")
		(17 "Dwgs.User" user "User.Drawings")
		(19 "Cmts.User" user "User.Comments")
		(21 "Eco1.User" user "User.Eco1")
		(23 "Eco2.User" user "User.Eco2")
		(25 "Edge.Cuts" user "Board Geometry/Outline")
		(27 "Margin" user)
		(31 "F.CrtYd" user "Package Geometry/Place Bound Top")
		(29 "B.CrtYd" user "Package Geometry/Place Bound Bottom")
		(35 "F.Fab" user "Ref Des/Assembly Top")
		(33 "B.Fab" user "Ref Des/Assembly Bottom")
	)
	(footprint ""
		(layer "F.Cu")
		(at 277.352252 -119.91467 180)
		(property "Reference" "R6201"
			(at 0 0 180)
			(layer "F.SilkS")
			(hide yes)
			(effects
				(font
					(size 1.27 1.27)
				)
			)
		)
		(property "Value" ""
			(at 0 0 180)
			(layer "F.Fab")
			(effects
				(font
					(size 1.27 1.27)
				)
			)
		)
		(duplicate_pad_numbers_are_jumpers no)
		(fp_line
			(start 0.7874 0.4064)
			(end -0.7874 0.4064)
			(stroke
				(width 0.1524)
				(type default)
			)
			(layer "F.SilkS")
		)
		(fp_line
			(start 0.7874 -0.4064)
			(end 0.7874 0.4064)
			(stroke
				(width 0.1524)
				(type default)
			)
			(layer "F.SilkS")
		)
		(fp_line
			(start -0.7874 0.4064)
			(end -0.7874 -0.4064)
			(stroke
				(width 0.1524)
				(type default)
			)
			(layer "F.SilkS")
		)
		(fp_line
			(start -0.7874 -0.4064)
			(end 0.7874 -0.4064)
			(stroke
				(width 0.1524)
				(type default)
			)
			(layer "F.SilkS")
		)
		(fp_line
			(start 0.67945 0.3048)
			(end 0.120396 0.3048)
			(stroke
				(width 0.1)
				(type default)
			)
			(layer "F.Fab")
		)
		(fp_line
			(start 0.67945 -0.3048)
			(end 0.67945 0.3048)
			(stroke
				(width 0.1)
				(type default)
			)
			(layer "F.Fab")
		)
		(fp_line
			(start 0.12065 -0.2794)
			(end 0.12065 -0.3048)
			(stroke
				(width 0.1)
				(type default)
			)
			(layer "F.Fab")
		)
		(fp_line
			(start 0.12065 -0.3048)
			(end 0.67945 -0.3048)
			(stroke
				(width 0.1)
				(type default)
			)
			(layer "F.Fab")
		)
		(fp_line
			(start 0.120396 0.3048)
			(end 0.120396 0.2794)
			(stroke
				(width 0.1)
				(type default)
			)
			(layer "F.Fab")
		)
		(fp_line
			(start 0.120396 0.2794)
			(end -0.12065 0.2794)
			(stroke
				(width 0.1)
				(type default)
			)
			(layer "F.Fab")
		)
		(fp_line
			(start -0.12065 0.3048)
			(end -0.67945 0.3048)
			(stroke
				(width 0.1)
				(type default)
			)
			(layer "F.Fab")
		)
		(fp_line
			(start -0.12065 0.2794)
			(end -0.12065 0.3048)
			(stroke
				(width 0.1)
				(type default)
			)
			(layer "F.Fab")
		)
		(fp_line
			(start -0.12065 -0.2794)
			(end 0.12065 -0.2794)
			(stroke
				(width 0.1)
				(type default)
			)
			(layer "F.Fab")
		)
		(fp_line
			(start -0.12065 -0.305054)
			(end -0.12065 -0.2794)
			(stroke
				(width 0.1)
				(type default)
			)
			(layer "F.Fab")
		)
		(fp_line
			(start -0.67945 0.3048)
			(end -0.67945 -0.305054)
			(stroke
				(width 0.1)
				(type default)
			)
			(layer "F.Fab")
		)
		(fp_line
			(start -0.67945 -0.305054)
			(end -0.12065 -0.305054)
			(stroke
				(width 0.1)
				(type default)
			)
			(layer "F.Fab")
		)
		(pad "1" smd circle
			(at -0.40005 0 180)
			(size 0 0)
			(layers "F.Cu" "F.Mask" "F.Paste")
			(net "SMB_USB_CPU0_HUB1_SCL_R")
		)
		(pad "2" smd circle
			(at 0.40005 0 180)
			(size 0 0)
			(layers "F.Cu" "F.Mask" "F.Paste")
			(net "SMB_USB_CPU0_HUB1_SCL")
		)
	)
	(footprint ""
		(layer "F.Cu")
		(at 26.954734 -394.733526 180)
		(property "Reference" "PC6633_2"
			(at 0 0 180)
			(layer "F.SilkS")
			(hide yes)
			(effects
				(font
					(size 1.27 1.27)
				)
			)
		)
		(property "Value" ""
			(at 0 0 180)
			(layer "F.Fab")
			(effects
				(font
					(size 1.27 1.27)
				)
			)
		)
		(duplicate_pad_numbers_are_jumpers no)
		(fp_line
			(start 0.7874 0.4064)
			(end -0.7874 0.4064)
			(stroke
				(width 0.1524)
				(type default)
			)
			(layer "F.SilkS")
		)
		(fp_line
			(start 0.7874 -0.4064)
			(end 0.7874 0.4064)
			(stroke
				(width 0.1524)
				(type default)
			)
			(layer "F.SilkS")
		)
		(fp_line
			(start -0.7874 0.4064)
			(end -0.7874 -0.4064)
			(stroke
				(width 0.1524)
				(type default)
			)
			(layer "F.SilkS")
		)
		(fp_line
			(start -0.7874 -0.4064)
			(end 0.7874 -0.4064)
			(stroke
				(width 0.1524)
				(type default)
			)
			(layer "F.SilkS")
		)
		(fp_line
			(start 0.67945 0.3048)
			(end 0.120396 0.3048)
			(stroke
				(width 0.1)
				(type default)
			)
			(layer "F.Fab")
		)
		(fp_line
			(start 0.67945 -0.3048)
			(end 0.67945 0.3048)
			(stroke
				(width 0.1)
				(type default)
			)
			(layer "F.Fab")
		)
		(fp_line
			(start 0.12065 -0.2794)
			(end 0.12065 -0.3048)
			(stroke
				(width 0.1)
				(type default)
			)
			(layer "F.Fab")
		)
		(fp_line
			(start 0.12065 -0.3048)
			(end 0.67945 -0.3048)
			(stroke
				(width 0.1)
				(type default)
			)
			(layer "F.Fab")
		)
		(fp_line
			(start 0.120396 0.3048)
			(end 0.120396 0.2794)
			(stroke
				(width 0.1)
				(type default)
			)
			(layer "F.Fab")
		)
		(fp_line
			(start 0.120396 0.2794)
			(end -0.12065 0.2794)
			(stroke
				(width 0.1)
				(type default)
			)
			(layer "F.Fab")
		)
		(fp_line
			(start -0.12065 0.3048)
			(end -0.67945 0.3048)
			(stroke
				(width 0.1)
				(type default)
			)
			(layer "F.Fab")
		)
		(fp_line
			(start -0.12065 0.2794)
			(end -0.12065 0.3048)
			(stroke
				(width 0.1)
				(type default)
			)
			(layer "F.Fab")
		)
		(fp_line
			(start -0.12065 -0.2794)
			(end 0.12065 -0.2794)
			(stroke
				(width 0.1)
				(type default)
			)
			(layer "F.Fab")
		)
		(fp_line
			(start -0.12065 -0.305054)
			(end -0.12065 -0.2794)
			(stroke
				(width 0.1)
				(type default)
			)
			(layer "F.Fab")
		)
		(fp_line
			(start -0.67945 0.3048)
			(end -0.67945 -0.305054)
			(stroke
				(width 0.1)
				(type default)
			)
			(layer "F.Fab")
		)
		(fp_line
			(start -0.67945 -0.305054)
			(end -0.12065 -0.305054)
			(stroke
				(width 0.1)
				(type default)
			)
			(layer "F.Fab")
		)
		(pad "1" smd circle
			(at -0.40005 0 180)
			(size 0 0)
			(layers "F.Cu" "F.Mask" "F.Paste")
			(net "SW_P12V_AUX_P0V9_RETIMER_CPU1_FLT")
		)
		(pad "2" smd circle
			(at 0.40005 0 180)
			(size 0 0)
			(layers "F.Cu" "F.Mask" "F.Paste")
			(net "GND")
		)
	)
)
